# BASEBOARD_FAB2 (Tioga Pass) — schematic netlist excerpt (pin names and nets, part order shuffled) for the footprints in the layout excerpt that follows; sources: Cadence DE-HDL packaged netlist, KiCad conversion of Wiwynn_Tioga_Pass_MB.brd

C3G5  CAP_A  47UF 4V 20% X5R  pkg 0603V  page 225 : A = PVDDQ_GHJ ; B = GND
C7A43  CAP  0.220UF 16V 10% X7R  pkg 0402  page 236 : A = VR_PVNN_PCH_PH1_BOOT ; B = VR_PVNN_PCH_PH1_PHASE
R6W27  RES  10.0 1% CHIP  pkg 0402  page 248 : A = SMB_CPU0_PE_HP_GTL_SDA ; B = SMB_CPU0_PE_HP_GTL_R_SDA

(kicad_pcb
	(version 20260206)
	(generator "pcbnew")
	(generator_version "10.0")
	(general
		(thickness 1.6)
		(legacy_teardrops no)
	)
	(paper "A4")
	(title_block
		(title "Wiwynn_Tioga_Pass_MB.brd")
		(comment 1 "Tioga Pass / footprints 287-289 of 4770")
	)
	(layers
		(0 "F.Cu" signal "TOP")
		(4 "In1.Cu" signal "L2GND")
		(6 "In2.Cu" signal "L3")
		(8 "In3.Cu" signal "L4GND")
		(10 "In4.Cu" signal "L5")
		(12 "In5.Cu" signal "L6GND")
		(14 "In6.Cu" signal "L7VCC")
		(16 "In7.Cu" signal "L8VCC")
		(18 "In8.Cu" signal "L9GND")
		(20 "In9.Cu" signal "L10")
		(22 "In10.Cu" signal "L11GND")
		(24 "In11.Cu" signal "L12")
		(26 "In12.Cu" signal "L13GND")
		(2 "B.Cu" signal "BOTTOM")
		(9 "F.Adhes" user "F.Adhesive")
		(11 "B.Adhes" user "B.Adhesive")
		(13 "F.Paste" user "Package Geometry/Pastemask Top")
		(15 "B.Paste" user "Package Geometry/Pastemask Bottom")
		(5 "F.SilkS" user "Ref Des/Silkscreen Top")
		(7 "B.SilkS" user "Ref Des/Silkscreen Bottom")
		(1 "F.Mask" user "Board Geometry/Soldermask Top")
		(3 "B.Mask" user "Board Geometry/Soldermask Bottom")
		(17 "Dwgs.User" user "User.Drawings")
		(19 "Cmts.User" user "User.Comments")
		(21 "Eco1.User" user "User.Eco1")
		(23 "Eco2.User" user "User.Eco2")
		(25 "Edge.Cuts" user "Board Geometry/Outline")
		(27 "Margin" user)
		(31 "F.CrtYd" user "Package Geometry/Place Bound Top")
		(29 "B.CrtYd" user "Package Geometry/Place Bound Bottom")
		(35 "F.Fab" user "Ref Des/Assembly Top")
		(33 "B.Fab" user "Ref Des/Assembly Bottom")
	)
	(footprint ""
		(layer "F.Cu")
		(at 379.5522 -158.0896)
		(property "Reference" "C7A43"
			(at 0 0 0)
			(layer "F.SilkS")
			(hide yes)
			(effects
				(font
					(size 1.27 1.27)
				)
			)
		)
		(property "Value" ""
			(at 0 0 0)
			(layer "F.Fab")
			(effects
				(font
					(size 1.27 1.27)
				)
			)
		)
		(duplicate_pad_numbers_are_jumpers no)
		(fp_poly
			(pts
				(xy 0.3048 -0.1016) (xy 0.3048 0.9906) (xy -0.3048 0.9906) (xy -0.3048 -0.1016)
			)
			(stroke
				(width 0)
				(type default)
			)
			(fill no)
			(layer "F.CrtYd")
		)
		(fp_line
			(start -0.3048 -0.1016)
			(end -0.3048 0.9906)
			(stroke
				(width 0.1)
				(type default)
			)
			(layer "F.Fab")
		)
		(fp_line
			(start -0.3048 0.9906)
			(end 0.3048 0.9906)
			(stroke
				(width 0.1)
				(type default)
			)
			(layer "F.Fab")
		)
		(fp_line
			(start 0.3048 -0.1016)
			(end -0.3048 -0.1016)
			(stroke
				(width 0.1)
				(type default)
			)
			(layer "F.Fab")
		)
		(fp_line
			(start 0.3048 0.9906)
			(end 0.3048 -0.1016)
			(stroke
				(width 0.1)
				(type default)
			)
			(layer "F.Fab")
		)
		(pad "1" smd rect
			(at 0 0)
			(size 0.508 0.508)
			(layers "F.Cu" "F.Mask" "F.Paste")
			(net "VR_PVNN_PCH_PH1_BOOT")
		)
		(pad "2" smd rect
			(at 0 0.889)
			(size 0.508 0.508)
			(layers "F.Cu" "F.Mask" "F.Paste")
			(net "VR_PVNN_PCH_PH1_PHASE")
		)
		(zone
			(layer "F.Cu")
			(hatch none 0.5)
			(connect_pads
				(clearance 0)
			)
			(min_thickness 0.25)
			(keepout
				(tracks allowed)
				(vias not_allowed)
				(pads allowed)
				(copperpour not_allowed)
				(footprints allowed)
			)
			(placement
				(enabled no)
				(sheetname "")
			)
			(fill
				(thermal_gap 0.5)
				(thermal_bridge_width 0.5)
				(island_removal_mode 0)
			)
			(polygon
				(pts
					(xy 379.2982 -157.8356) (xy 379.8062 -157.8356) (xy 379.8062 -157.4546) (xy 379.2982 -157.4546)
				)
			)
		)
		(zone
			(layer "F.Cu")
			(hatch none 0.5)
			(connect_pads
				(clearance 0)
			)
			(min_thickness 0.25)
			(keepout
				(tracks not_allowed)
				(vias allowed)
				(pads allowed)
				(copperpour not_allowed)
				(footprints allowed)
			)
			(placement
				(enabled no)
				(sheetname "")
			)
			(fill
				(thermal_gap 0.5)
				(thermal_bridge_width 0.5)
				(island_removal_mode 0)
			)
			(polygon
				(pts
					(xy 379.2982 -157.4546) (xy 379.8062 -157.4546) (xy 379.8062 -157.8356) (xy 379.2982 -157.8356)
				)
			)
		)
	)
	(footprint ""
		(layer "F.Cu")
		(at 107.8611 -3.3528 90)
		(property "Reference" "C3G5"
			(at 1.848866 0.752348 90)
			(unlocked yes)
			(layer "F.SilkS")
			(effects
				(font
					(size 1.27 0.9652)
					(thickness 0.1524)
				)
			)
		)
		(property "Value" ""
			(at 0 0 90)
			(layer "F.Fab")
			(effects
				(font
					(size 1.27 1.27)
				)
			)
		)
		(duplicate_pad_numbers_are_jumpers no)
		(fp_rect
			(start -0.500126 1.598422)
			(end 0.500126 -0.201422)
			(stroke
				(width 0)
				(type default)
			)
			(fill no)
			(layer "F.CrtYd")
		)
		(fp_line
			(start 0.500126 -0.201422)
			(end 0.500126 1.598422)
			(stroke
				(width 0.1)
				(type default)
			)
			(layer "F.Fab")
		)
		(fp_line
			(start -0.500126 -0.201422)
			(end 0.500126 -0.201422)
			(stroke
				(width 0.1)
				(type default)
			)
			(layer "F.Fab")
		)
		(fp_line
			(start 0.500126 1.598422)
			(end -0.500126 1.598422)
			(stroke
				(width 0.1)
				(type default)
			)
			(layer "F.Fab")
		)
		(fp_line
			(start -0.500126 1.598422)
			(end -0.500126 -0.201422)
			(stroke
				(width 0.1)
				(type default)
			)
			(layer "F.Fab")
		)
		(pad "1" smd rect
			(at 0 0)
			(size 0.889 0.9906)
			(layers "F.Cu" "F.Mask" "F.Paste")
			(net "PVDDQ_GHJ")
		)
		(pad "2" smd rect
			(at 0 1.397)
			(size 0.889 0.9906)
			(layers "F.Cu" "F.Mask" "F.Paste")
			(net "GND")
		)
		(zone
			(layer "F.Cu")
			(hatch none 0.5)
			(connect_pads
				(clearance 0)
			)
			(min_thickness 0.25)
			(keepout
				(tracks not_allowed)
				(vias allowed)
				(pads allowed)
				(copperpour not_allowed)
				(footprints allowed)
			)
			(placement
				(enabled no)
				(sheetname "")
			)
			(fill
				(thermal_gap 0.5)
				(thermal_bridge_width 0.5)
				(island_removal_mode 0)
			)
			(polygon
				(pts
					(xy 108.8136 -2.8575) (xy 108.8136 -3.8481) (xy 108.3056 -3.8481) (xy 108.3056 -2.8575)
				)
			)
		)
		(zone
			(layer "F.Cu")
			(hatch none 0.5)
			(connect_pads
				(clearance 0)
			)
			(min_thickness 0.25)
			(keepout
				(tracks allowed)
				(vias not_allowed)
				(pads allowed)
				(copperpour not_allowed)
				(footprints allowed)
			)
			(placement
				(enabled no)
				(sheetname "")
			)
			(fill
				(thermal_gap 0.5)
				(thermal_bridge_width 0.5)
				(island_removal_mode 0)
			)
			(polygon
				(pts
					(xy 108.8136 -2.8575) (xy 108.8136 -3.8481) (xy 108.3056 -3.8481) (xy 108.3056 -2.8575)
				)
			)
		)
	)
	(footprint ""
		(layer "F.Cu")
		(at 422.2877 -104.267 -90)
		(property "Reference" "R6W27"
			(at -0.8382 -0.67818 270)
			(unlocked yes)
			(layer "F.SilkS")
			(effects
				(font
					(size 0.4064 0.254)
					(thickness 0.1524)
				)
				(justify left)
			)
		)
		(property "Value" ""
			(at 0 0 270)
			(layer "F.Fab")
			(effects
				(font
					(size 1.27 1.27)
				)
			)
		)
		(duplicate_pad_numbers_are_jumpers no)
		(fp_poly
			(pts
				(xy -0.2794 -0.1016) (xy 0.2794 -0.1016) (xy 0.2794 0.9906) (xy -0.2794 0.9906)
			)
			(stroke
				(width 0)
				(type default)
			)
			(fill no)
			(layer "F.CrtYd")
		)
		(fp_line
			(start -0.2794 0.9906)
			(end 0.2794 0.9906)
			(stroke
				(width 0.1)
				(type default)
			)
			(layer "F.Fab")
		)
		(fp_line
			(start 0.2794 0.9906)
			(end 0.2794 -0.1016)
			(stroke
				(width 0.1)
				(type default)
			)
			(layer "F.Fab")
		)
		(fp_line
			(start -0.2794 -0.1016)
			(end -0.2794 0.9906)
			(stroke
				(width 0.1)
				(type default)
			)
			(layer "F.Fab")
		)
		(fp_line
			(start 0.2794 -0.1016)
			(end -0.2794 -0.1016)
			(stroke
				(width 0.1)
				(type default)
			)
			(layer "F.Fab")
		)
		(pad "1" smd rect
			(at 0 0 270)
			(size 0.508 0.508)
			(layers "F.Cu" "F.Mask" "F.Paste")
			(net "SMB_CPU0_PE_HP_GTL_SDA")
		)
		(pad "2" smd rect
			(at 0 0.889 270)
			(size 0.508 0.508)
			(layers "F.Cu" "F.Mask" "F.Paste")
			(net "SMB_CPU0_PE_HP_GTL_R_SDA")
		)
		(zone
			(layer "F.Cu")
			(hatch none 0.5)
			(connect_pads
				(clearance 0)
			)
			(min_thickness 0.25)
			(keepout
				(tracks not_allowed)
				(vias allowed)
				(pads allowed)
				(copperpour not_allowed)
				(footprints allowed)
			)
			(placement
				(enabled no)
				(sheetname "")
			)
			(fill
				(thermal_gap 0.5)
				(thermal_bridge_width 0.5)
				(island_removal_mode 0)
			)
			(polygon
				(pts
					(xy 421.6527 -104.521) (xy 421.6527 -104.013) (xy 422.0337 -104.013) (xy 422.0337 -104.521)
				)
			)
		)
		(zone
			(layer "F.Cu")
			(hatch none 0.5)
			(connect_pads
				(clearance 0)
			)
			(min_thickness 0.25)
			(keepout
				(tracks allowed)
				(vias not_allowed)
				(pads allowed)
				(copperpour not_allowed)
				(footprints allowed)
			)
			(placement
				(enabled no)
				(sheetname "")
			)
			(fill
				(thermal_gap 0.5)
				(thermal_bridge_width 0.5)
				(island_removal_mode 0)
			)
			(polygon
				(pts
					(xy 422.0337 -104.521) (xy 422.0337 -104.013) (xy 421.6527 -104.013) (xy 421.6527 -104.521)
				)
			)
		)
	)
)
